# T6G (Grand Teton) — schematic netlist excerpt (pin names and nets, part order shuffled) for the footprints in the layout excerpt that follows; sources: Cadence DE-HDL packaged netlist, KiCad conversion of 04192023_DAF0TMB3IC0_F0TG_MB_C_brd_V02_OCP.brd

PC2154  Q_CAP  1UF 25V 10% X6S  pkg C0402  page 135 : A = P12V_AUX ; B = GND
PL16  Q_INDUCTOR  0.22UH/33A IND  pkg SMLF  page 206 : \1\ = IND_PVDDIO_P0_CPL0 ; \2\ = GND
C2535  Q_CAP  22UF 4V 20% X6S  pkg C0402  page 70 : A = PVDDCR_SOC_P0 ; B = GND

(kicad_pcb
	(version 20260206)
	(generator "pcbnew")
	(generator_version "10.0")
	(general
		(thickness 1.6)
		(legacy_teardrops no)
	)
	(paper "A4")
	(title_block
		(title "04192023_DAF0TMB3IC0_F0TG_MB_C_brd_V02_OCP.brd")
		(comment 1 "Grand Teton / footprints 3063-3065 of 8354")
	)
	(layers
		(0 "F.Cu" signal "TOP")
		(4 "In1.Cu" signal "GND")
		(6 "In2.Cu" signal "IN1")
		(8 "In3.Cu" signal "GND1")
		(10 "In4.Cu" signal "IN2")
		(12 "In5.Cu" signal "GND2")
		(14 "In6.Cu" signal "IN3")
		(16 "In7.Cu" signal "GND3")
		(18 "In8.Cu" signal "VCC")
		(20 "In9.Cu" signal "VCC1")
		(22 "In10.Cu" signal "GND4")
		(24 "In11.Cu" signal "IN4")
		(26 "In12.Cu" signal "GND5")
		(28 "In13.Cu" signal "IN5")
		(30 "In14.Cu" signal "GND6")
		(32 "In15.Cu" signal "IN6")
		(34 "In16.Cu" signal "GND7")
		(2 "B.Cu" signal "BOTTOM")
		(9 "F.Adhes" user "F.Adhesive")
		(11 "B.Adhes" user "B.Adhesive")
		(13 "F.Paste" user "Package Geometry/Pastemask Top")
		(15 "B.Paste" user "Package Geometry/Pastemask Bottom")
		(5 "F.SilkS" user "Ref Des/Silkscreen Top")
		(7 "B.SilkS" user "Ref Des/Silkscreen Bottom")
		(1 "F.Mask" user "Board Geometry/Soldermask Top")
		(3 "B.Mask" user "Board Geometry/Soldermask Bottom")
		(17 "Dwgs.User" user "User.Drawings")
		(19 "Cmts.User" user "User.Comments")
		(21 "Eco1.User" user "User.Eco1")
		(23 "Eco2.User" user "User.Eco2")
		(25 "Edge.Cuts" user "Board Geometry/Outline")
		(27 "Margin" user)
		(31 "F.CrtYd" user "Package Geometry/Place Bound Top")
		(29 "B.CrtYd" user "Package Geometry/Place Bound Bottom")
		(35 "F.Fab" user "Ref Des/Assembly Top")
		(33 "B.Fab" user "Ref Des/Assembly Bottom")
	)
	(footprint ""
		(layer "F.Cu")
		(at 448.177412 -30.131258 90)
		(property "Reference" "PC2154"
			(at 0 0 90)
			(layer "F.SilkS")
			(hide yes)
			(effects
				(font
					(size 1.27 1.27)
				)
			)
		)
		(property "Value" ""
			(at 0 0 90)
			(layer "F.Fab")
			(effects
				(font
					(size 1.27 1.27)
				)
			)
		)
		(duplicate_pad_numbers_are_jumpers no)
		(fp_line
			(start 0.7874 -0.4064)
			(end 0.7874 0.4064)
			(stroke
				(width 0.1524)
				(type default)
			)
			(layer "F.SilkS")
		)
		(fp_line
			(start -0.7874 -0.4064)
			(end 0.7874 -0.4064)
			(stroke
				(width 0.1524)
				(type default)
			)
			(layer "F.SilkS")
		)
		(fp_line
			(start 0.7874 0.4064)
			(end -0.7874 0.4064)
			(stroke
				(width 0.1524)
				(type default)
			)
			(layer "F.SilkS")
		)
		(fp_line
			(start -0.7874 0.4064)
			(end -0.7874 -0.4064)
			(stroke
				(width 0.1524)
				(type default)
			)
			(layer "F.SilkS")
		)
		(fp_line
			(start -0.12065 -0.305054)
			(end -0.12065 -0.2794)
			(stroke
				(width 0.1)
				(type default)
			)
			(layer "F.Fab")
		)
		(fp_line
			(start -0.67945 -0.305054)
			(end -0.12065 -0.305054)
			(stroke
				(width 0.1)
				(type default)
			)
			(layer "F.Fab")
		)
		(fp_line
			(start 0.67945 -0.3048)
			(end 0.67945 0.3048)
			(stroke
				(width 0.1)
				(type default)
			)
			(layer "F.Fab")
		)
		(fp_line
			(start 0.12065 -0.3048)
			(end 0.67945 -0.3048)
			(stroke
				(width 0.1)
				(type default)
			)
			(layer "F.Fab")
		)
		(fp_line
			(start 0.12065 -0.2794)
			(end 0.12065 -0.3048)
			(stroke
				(width 0.1)
				(type default)
			)
			(layer "F.Fab")
		)
		(fp_line
			(start -0.12065 -0.2794)
			(end 0.12065 -0.2794)
			(stroke
				(width 0.1)
				(type default)
			)
			(layer "F.Fab")
		)
		(fp_line
			(start 0.120396 0.2794)
			(end -0.12065 0.2794)
			(stroke
				(width 0.1)
				(type default)
			)
			(layer "F.Fab")
		)
		(fp_line
			(start -0.12065 0.2794)
			(end -0.12065 0.3048)
			(stroke
				(width 0.1)
				(type default)
			)
			(layer "F.Fab")
		)
		(fp_line
			(start 0.67945 0.3048)
			(end 0.120396 0.3048)
			(stroke
				(width 0.1)
				(type default)
			)
			(layer "F.Fab")
		)
		(fp_line
			(start 0.120396 0.3048)
			(end 0.120396 0.2794)
			(stroke
				(width 0.1)
				(type default)
			)
			(layer "F.Fab")
		)
		(fp_line
			(start -0.12065 0.3048)
			(end -0.67945 0.3048)
			(stroke
				(width 0.1)
				(type default)
			)
			(layer "F.Fab")
		)
		(fp_line
			(start -0.67945 0.3048)
			(end -0.67945 -0.305054)
			(stroke
				(width 0.1)
				(type default)
			)
			(layer "F.Fab")
		)
		(pad "1" smd circle
			(at -0.40005 0 90)
			(size 0 0)
			(layers "F.Cu" "F.Mask" "F.Paste")
			(net "P12V_AUX")
		)
		(pad "2" smd circle
			(at 0.40005 0 90)
			(size 0 0)
			(layers "F.Cu" "F.Mask" "F.Paste")
			(net "GND")
		)
	)
	(footprint ""
		(layer "F.Cu")
		(at 267.896848 -339.218778 90)
		(property "Reference" "PL16"
			(at -3.302 -3.978148 90)
			(unlocked yes)
			(layer "F.SilkS")
			(effects
				(font
					(size 0.7874 0.5842)
					(thickness 0.1524)
				)
				(justify left)
			)
		)
		(property "Value" ""
			(at 0 0 90)
			(layer "F.Fab")
			(effects
				(font
					(size 1.27 1.27)
				)
			)
		)
		(duplicate_pad_numbers_are_jumpers no)
		(fp_line
			(start 3.24993 -3.24993)
			(end 3.24993 -2.2352)
			(stroke
				(width 0.1524)
				(type default)
			)
			(layer "F.SilkS")
		)
		(fp_line
			(start -3.24993 -3.24993)
			(end 3.24993 -3.24993)
			(stroke
				(width 0.1524)
				(type default)
			)
			(layer "F.SilkS")
		)
		(fp_line
			(start -3.24993 -2.2352)
			(end -3.24993 -3.24993)
			(stroke
				(width 0.1524)
				(type default)
			)
			(layer "F.SilkS")
		)
		(fp_line
			(start 3.24993 2.2352)
			(end 3.24993 3.24993)
			(stroke
				(width 0.1524)
				(type default)
			)
			(layer "F.SilkS")
		)
		(fp_line
			(start 3.24993 3.24993)
			(end -3.24993 3.24993)
			(stroke
				(width 0.1524)
				(type default)
			)
			(layer "F.SilkS")
		)
		(fp_line
			(start -3.24993 3.24993)
			(end -3.24993 2.2352)
			(stroke
				(width 0.1524)
				(type default)
			)
			(layer "F.SilkS")
		)
		(fp_line
			(start 3.24993 -3.24993)
			(end 3.24993 3.24993)
			(stroke
				(width 0.1)
				(type default)
			)
			(layer "F.Fab")
		)
		(fp_line
			(start -3.24993 -3.24993)
			(end 3.24993 -3.24993)
			(stroke
				(width 0.1)
				(type default)
			)
			(layer "F.Fab")
		)
		(fp_line
			(start 3.24993 3.24993)
			(end -3.24993 3.24993)
			(stroke
				(width 0.1)
				(type default)
			)
			(layer "F.Fab")
		)
		(fp_line
			(start -3.24993 3.24993)
			(end -3.24993 -3.24993)
			(stroke
				(width 0.1)
				(type default)
			)
			(layer "F.Fab")
		)
		(pad "1" smd rect
			(at -2.29997 0 90)
			(size 2.0066 4.2164)
			(layers "F.Cu" "F.Mask" "F.Paste")
			(net "IND_PVDDIO_P0_CPL0")
		)
		(pad "2" smd rect
			(at 2.29997 0 90)
			(size 2.0066 4.2164)
			(layers "F.Cu" "F.Mask" "F.Paste")
			(net "GND")
		)
	)
	(footprint ""
		(layer "F.Cu")
		(at 365.835692 -255.554988 180)
		(property "Reference" "C2535"
			(at 0 0 180)
			(layer "F.SilkS")
			(hide yes)
			(effects
				(font
					(size 1.27 1.27)
				)
			)
		)
		(property "Value" ""
			(at 0 0 180)
			(layer "F.Fab")
			(effects
				(font
					(size 1.27 1.27)
				)
			)
		)
		(duplicate_pad_numbers_are_jumpers no)
		(fp_line
			(start 0.7874 0.4064)
			(end -0.7874 0.4064)
			(stroke
				(width 0.1524)
				(type default)
			)
			(layer "F.SilkS")
		)
		(fp_line
			(start 0.7874 -0.4064)
			(end 0.7874 0.4064)
			(stroke
				(width 0.1524)
				(type default)
			)
			(layer "F.SilkS")
		)
		(fp_line
			(start -0.7874 0.4064)
			(end -0.7874 -0.4064)
			(stroke
				(width 0.1524)
				(type default)
			)
			(layer "F.SilkS")
		)
		(fp_line
			(start -0.7874 -0.4064)
			(end 0.7874 -0.4064)
			(stroke
				(width 0.1524)
				(type default)
			)
			(layer "F.SilkS")
		)
		(fp_line
			(start 0.67945 0.3048)
			(end 0.120396 0.3048)
			(stroke
				(width 0.1)
				(type default)
			)
			(layer "F.Fab")
		)
		(fp_line
			(start 0.67945 -0.3048)
			(end 0.67945 0.3048)
			(stroke
				(width 0.1)
				(type default)
			)
			(layer "F.Fab")
		)
		(fp_line
			(start 0.12065 -0.2794)
			(end 0.12065 -0.3048)
			(stroke
				(width 0.1)
				(type default)
			)
			(layer "F.Fab")
		)
		(fp_line
			(start 0.12065 -0.3048)
			(end 0.67945 -0.3048)
			(stroke
				(width 0.1)
				(type default)
			)
			(layer "F.Fab")
		)
		(fp_line
			(start 0.120396 0.3048)
			(end 0.120396 0.2794)
			(stroke
				(width 0.1)
				(type default)
			)
			(layer "F.Fab")
		)
		(fp_line
			(start 0.120396 0.2794)
			(end -0.12065 0.2794)
			(stroke
				(width 0.1)
				(type default)
			)
			(layer "F.Fab")
		)
		(fp_line
			(start -0.12065 0.3048)
			(end -0.67945 0.3048)
			(stroke
				(width 0.1)
				(type default)
			)
			(layer "F.Fab")
		)
		(fp_line
			(start -0.12065 0.2794)
			(end -0.12065 0.3048)
			(stroke
				(width 0.1)
				(type default)
			)
			(layer "F.Fab")
		)
		(fp_line
			(start -0.12065 -0.2794)
			(end 0.12065 -0.2794)
			(stroke
				(width 0.1)
				(type default)
			)
			(layer "F.Fab")
		)
		(fp_line
			(start -0.12065 -0.305054)
			(end -0.12065 -0.2794)
			(stroke
				(width 0.1)
				(type default)
			)
			(layer "F.Fab")
		)
		(fp_line
			(start -0.67945 0.3048)
			(end -0.67945 -0.305054)
			(stroke
				(width 0.1)
				(type default)
			)
			(layer "F.Fab")
		)
		(fp_line
			(start -0.67945 -0.305054)
			(end -0.12065 -0.305054)
			(stroke
				(width 0.1)
				(type default)
			)
			(layer "F.Fab")
		)
		(pad "1" smd circle
			(at -0.40005 0 180)
			(size 0 0)
			(layers "F.Cu" "F.Mask" "F.Paste")
			(net "PVDDCR_SOC_P0")
		)
		(pad "2" smd circle
			(at 0.40005 0 180)
			(size 0 0)
			(layers "F.Cu" "F.Mask" "F.Paste")
			(net "GND")
		)
	)
)
